(kicad_pcb
	(version 20260206)
	(generator "pcbnew")
	(generator_version "10.0")
	(general
		(thickness 1.6)
		(legacy_teardrops no)
	)
	(paper "A4")
	(title_block
		(title "Wiwynn_Tioga_Pass_MB.brd")
		(comment 1 "Tioga Pass / footprints 366-367 of 4770")
	)
	(layers
		(0 "F.Cu" signal "TOP")
		(4 "In1.Cu" signal "L2GND")
		(6 "In2.Cu" signal "L3")
		(8 "In3.Cu" signal "L4GND")
		(10 "In4.Cu" signal "L5")
		(12 "In5.Cu" signal "L6GND")
		(14 "In6.Cu" signal "L7VCC")
		(16 "In7.Cu" signal "L8VCC")
		(18 "In8.Cu" signal "L9GND")
		(20 "In9.Cu" signal "L10")
		(22 "In10.Cu" signal "L11GND")
		(24 "In11.Cu" signal "L12")
		(26 "In12.Cu" signal "L13GND")
		(2 "B.Cu" signal "BOTTOM")
		(9 "F.Adhes" user "F.Adhesive")
		(11 "B.Adhes" user "B.Adhesive")
		(13 "F.Paste" user "Package Geometry/Pastemask Top")
		(15 "B.Paste" user "Package Geometry/Pastemask Bottom")
		(5 "F.SilkS" user "Ref Des/Silkscreen Top")
		(7 "B.SilkS" user "Ref Des/Silkscreen Bottom")
		(1 "F.Mask" user "Board Geometry/Soldermask Top")
		(3 "B.Mask" user "Board Geometry/Soldermask Bottom")
		(17 "Dwgs.User" user "User.Drawings")
		(19 "Cmts.User" user "User.Comments")
		(21 "Eco1.User" user "User.Eco1")
		(23 "Eco2.User" user "User.Eco2")
		(25 "Edge.Cuts" user "Board Geometry/Outline")
		(27 "Margin" user)
		(31 "F.CrtYd" user "Package Geometry/Place Bound Top")
		(29 "B.CrtYd" user "Package Geometry/Place Bound Bottom")
		(35 "F.Fab" user "Ref Des/Assembly Top")
		(33 "B.Fab" user "Ref Des/Assembly Bottom")
	)
	(footprint ""
		(layer "F.Cu")
		(at 340.38286 -2.02438 90)
		(property "Reference" "CT53"
			(at -0.8382 -0.67818 90)
			(unlocked yes)
			(layer "F.SilkS")
			(effects
				(font
					(size 0.4064 0.254)
					(thickness 0.1524)
				)
				(justify left)
			)
		)
		(property "Value" ""
			(at 0 0 90)
			(layer "F.Fab")
			(effects
				(font
					(size 1.27 1.27)
				)
			)
		)
		(duplicate_pad_numbers_are_jumpers no)
		(fp_poly
			(pts
				(xy 0.3048 -0.1016) (xy 0.3048 0.9906) (xy -0.3048 0.9906) (xy -0.3048 -0.1016)
			)
			(stroke
				(width 0)
				(type default)
			)
			(fill no)
			(layer "F.CrtYd")
		)
		(fp_line
			(start 0.3048 -0.1016)
			(end -0.3048 -0.1016)
			(stroke
				(width 0.1)
				(type default)
			)
			(layer "F.Fab")
		)
		(fp_line
			(start -0.3048 -0.1016)
			(end -0.3048 0.9906)
			(stroke
				(width 0.1)
				(type default)
			)
			(layer "F.Fab")
		)
		(fp_line
			(start 0.3048 0.9906)
			(end 0.3048 -0.1016)
			(stroke
				(width 0.1)
				(type default)
			)
			(layer "F.Fab")
		)
		(fp_line
			(start -0.3048 0.9906)
			(end 0.3048 0.9906)
			(stroke
				(width 0.1)
				(type default)
			)
			(layer "F.Fab")
		)
		(pad "1" smd rect
			(at 0 0 90)
			(size 0.508 0.508)
			(layers "F.Cu" "F.Mask" "F.Paste")
			(net "VR_PVDDQ_ABC_PH2_SW")
		)
		(pad "2" smd rect
			(at 0 0.889 90)
			(size 0.508 0.508)
			(layers "F.Cu" "F.Mask" "F.Paste")
			(net "VR_PVDDQ_ABC_PH2_SW_RC")
		)
		(zone
			(layer "F.Cu")
			(hatch none 0.5)
			(connect_pads
				(clearance 0)
			)
			(min_thickness 0.25)
			(keepout
				(tracks allowed)
				(vias not_allowed)
				(pads allowed)
				(copperpour not_allowed)
				(footprints allowed)
			)
			(placement
				(enabled no)
				(sheetname "")
			)
			(fill
				(thermal_gap 0.5)
				(thermal_bridge_width 0.5)
				(island_removal_mode 0)
			)
			(polygon
				(pts
					(xy 340.63686 -1.77038) (xy 340.63686 -2.27838) (xy 341.01786 -2.27838) (xy 341.01786 -1.77038)
				)
			)
		)
		(zone
			(layer "F.Cu")
			(hatch none 0.5)
			(connect_pads
				(clearance 0)
			)
			(min_thickness 0.25)
			(keepout
				(tracks not_allowed)
				(vias allowed)
				(pads allowed)
				(copperpour not_allowed)
				(footprints allowed)
			)
			(placement
				(enabled no)
				(sheetname "")
			)
			(fill
				(thermal_gap 0.5)
				(thermal_bridge_width 0.5)
				(island_removal_mode 0)
			)
			(polygon
				(pts
					(xy 341.01786 -1.77038) (xy 341.01786 -2.27838) (xy 340.63686 -2.27838) (xy 340.63686 -1.77038)
				)
			)
		)
	)
	(footprint ""
		(layer "F.Cu")
		(at 289.222434 -77.449934 180)
		(property "Reference" "XRU1"
			(at -17.990566 32.886396 0)
			(unlocked yes)
			(layer "F.SilkS")
			(effects
				(font
					(size 0.7874 0.5842)
					(thickness 0.1524)
				)
				(justify left)
			)
		)
		(property "Value" ""
			(at 0 0 180)
			(layer "F.Fab")
			(effects
				(font
					(size 1.27 1.27)
				)
			)
		)
		(duplicate_pad_numbers_are_jumpers no)
		(fp_line
			(start 19.221958 -10.649966)
			(end 19.221958 -29.399992)
			(stroke
				(width 0.1524)
				(type default)
			)
			(layer "F.SilkS")
		)
		(fp_line
			(start 19.221958 -29.399992)
			(end 18.62201 -29.399992)
			(stroke
				(width 0.1524)
				(type default)
			)
			(layer "F.SilkS")
		)
		(fp_line
			(start 18.62201 28.599892)
			(end 18.62201 8.850122)
			(stroke
				(width 0.1524)
				(type default)
			)
			(layer "F.SilkS")
		)
		(fp_line
			(start 18.62201 27.599894)
			(end 18.62201 8.850122)
			(stroke
				(width 0.1524)
				(type default)
			)
			(layer "F.SilkS")
		)
		(fp_line
			(start 18.62201 8.850122)
			(end 12.761976 8.850122)
			(stroke
				(width 0.1524)
				(type default)
			)
			(layer "F.SilkS")
		)
		(fp_line
			(start 18.62201 8.850122)
			(end 12.761976 8.850122)
			(stroke
				(width 0.1524)
				(type default)
			)
			(layer "F.SilkS")
		)
		(fp_line
			(start 18.62201 -29.399992)
			(end 18.62201 -30.39999)
			(stroke
				(width 0.1524)
				(type default)
			)
			(layer "F.SilkS")
		)
		(fp_line
			(start 18.62201 -30.39999)
			(end 17.622012 -30.39999)
			(stroke
				(width 0.1524)
				(type default)
			)
			(layer "F.SilkS")
		)
		(fp_line
			(start 17.622012 28.599892)
			(end 18.62201 28.599892)
			(stroke
				(width 0.1524)
				(type default)
			)
			(layer "F.SilkS")
		)
		(fp_line
			(start 17.622012 27.599894)
			(end 17.622012 28.599892)
			(stroke
				(width 0.1524)
				(type default)
			)
			(layer "F.SilkS")
		)
		(fp_line
			(start 17.622012 -29.399992)
			(end -14.777974 -29.399992)
			(stroke
				(width 0.1524)
				(type default)
			)
			(layer "F.SilkS")
		)
		(fp_line
			(start 17.622012 -30.39999)
			(end 17.622012 -29.399992)
			(stroke
				(width 0.1524)
				(type default)
			)
			(layer "F.SilkS")
		)
		(fp_line
			(start 12.761976 8.850122)
			(end 6.171946 4.890008)
			(stroke
				(width 0.1524)
				(type default)
			)
			(layer "F.SilkS")
		)
		(fp_line
			(start 12.761976 8.850122)
			(end 6.171946 4.890008)
			(stroke
				(width 0.1524)
				(type default)
			)
			(layer "F.SilkS")
		)
		(fp_line
			(start 12.761976 -10.649966)
			(end 19.221958 -10.649966)
			(stroke
				(width 0.1524)
				(type default)
			)
			(layer "F.SilkS")
		)
		(fp_line
			(start 12.761976 -10.649966)
			(end 19.221958 -10.649966)
			(stroke
				(width 0.1524)
				(type default)
			)
			(layer "F.SilkS")
		)
		(fp_line
			(start 6.171946 4.890008)
			(end 6.171946 -6.690106)
			(stroke
				(width 0.1524)
				(type default)
			)
			(layer "F.SilkS")
		)
		(fp_line
			(start 6.171946 4.890008)
			(end 6.171946 -6.690106)
			(stroke
				(width 0.1524)
				(type default)
			)
			(layer "F.SilkS")
		)
		(fp_line
			(start 6.171946 -6.690106)
			(end 12.761976 -10.649966)
			(stroke
				(width 0.1524)
				(type default)
			)
			(layer "F.SilkS")
		)
		(fp_line
			(start 6.171946 -6.690106)
			(end 12.761976 -10.649966)
			(stroke
				(width 0.1524)
				(type default)
			)
			(layer "F.SilkS")
		)
		(fp_line
			(start -14.777974 30.150054)
			(end -14.777974 27.599894)
			(stroke
				(width 0.1524)
				(type default)
			)
			(layer "F.SilkS")
		)
		(fp_line
			(start -14.777974 27.599894)
			(end 17.622012 27.599894)
			(stroke
				(width 0.1524)
				(type default)
			)
			(layer "F.SilkS")
		)
		(fp_line
			(start -14.777974 -29.399992)
			(end -14.777974 -31.949898)
			(stroke
				(width 0.1524)
				(type default)
			)
			(layer "F.SilkS")
		)
		(fp_line
			(start -14.777974 -31.949898)
			(end -21.77796 -31.949898)
			(stroke
				(width 0.1524)
				(type default)
			)
			(layer "F.SilkS")
		)
		(fp_line
			(start -17.777968 2.100072)
			(end -18.278094 2.100072)
			(stroke
				(width 0.1524)
				(type default)
			)
			(layer "F.SilkS")
		)
		(fp_line
			(start -17.777968 -3.899916)
			(end -17.777968 2.100072)
			(stroke
				(width 0.1524)
				(type default)
			)
			(layer "F.SilkS")
		)
		(fp_line
			(start -18.278094 3.599942)
			(end -21.77796 7.100062)
			(stroke
				(width 0.1524)
				(type default)
			)
			(layer "F.SilkS")
		)
		(fp_line
			(start -18.278094 2.100072)
			(end -18.278094 3.599942)
			(stroke
				(width 0.1524)
				(type default)
			)
			(layer "F.SilkS")
		)
		(fp_line
			(start -18.278094 -3.899916)
			(end -17.777968 -3.899916)
			(stroke
				(width 0.1524)
				(type default)
			)
			(layer "F.SilkS")
		)
		(fp_line
			(start -18.278094 -5.40004)
			(end -18.278094 -3.899916)
			(stroke
				(width 0.1524)
				(type default)
			)
			(layer "F.SilkS")
		)
		(fp_line
			(start -21.77796 30.150054)
			(end -14.777974 30.150054)
			(stroke
				(width 0.1524)
				(type default)
			)
			(layer "F.SilkS")
		)
		(fp_line
			(start -21.77796 7.100062)
			(end -21.77796 30.150054)
			(stroke
				(width 0.1524)
				(type default)
			)
			(layer "F.SilkS")
		)
		(fp_line
			(start -21.77796 -8.899906)
			(end -18.278094 -5.40004)
			(stroke
				(width 0.1524)
				(type default)
			)
			(layer "F.SilkS")
		)
		(fp_line
			(start -21.77796 -31.949898)
			(end -21.77796 -8.899906)
			(stroke
				(width 0.1524)
				(type default)
			)
			(layer "F.SilkS")
		)
		(fp_circle
			(center -28.829 -29.215334)
			(end -28.956 -29.215334)
			(stroke
				(width 0.254)
				(type default)
			)
			(fill no)
			(layer "F.SilkS")
		)
		(fp_poly
			(pts
				(xy -21.762212 30.150054) (xy -14.777974 30.150054) (xy -14.777974 27.599894) (xy 17.622012 27.599894)
				(xy 17.622012 28.599892) (xy 18.62201 28.599892) (xy 18.62201 8.850122) (xy 12.761976 8.850122)
				(xy 6.171946 4.890008) (xy 6.171946 -6.690106) (xy 12.761976 -10.649966) (xy 19.221958 -10.649966)
				(xy 19.221958 -29.399992) (xy 18.62201 -29.399992) (xy 18.62201 -30.39999) (xy 17.622012 -30.39999)
				(xy 17.622012 -29.399992) (xy -14.777974 -29.399992) (xy -14.777974 -31.949898) (xy -21.77796 -31.949898)
				(xy -21.77796 -8.899906) (xy -18.278094 -5.40004) (xy -18.278094 -3.899916) (xy -17.777968 -3.899916)
				(xy -17.777968 2.100072) (xy -18.278094 2.100072) (xy -18.278094 3.599942) (xy -21.77796 7.100062)
				(xy -21.77796 15.059406) (xy -20.051776 15.059406) (xy -20.048728 15.001748) (xy -20.04441 14.966442)
				(xy -20.036282 14.912086) (xy -20.02536 14.859762) (xy -20.007326 14.788134) (xy -19.98345 14.720062)
				(xy -19.96821 14.680692) (xy -19.937222 14.614144) (xy -19.910552 14.565376) (xy -19.878294 14.512544)
				(xy -19.833082 14.449044) (xy -19.790918 14.396466) (xy -19.746468 14.348714) (xy -19.70151 14.305026)
				(xy -19.629628 14.236954) (xy -19.548856 14.18336) (xy -19.442684 14.125956) (xy -19.368516 14.092936)
				(xy -19.202654 14.039342) (xy -19.046698 14.018514) (xy -18.893282 14.020546) (xy -18.758662 14.041882)
				(xy -18.615152 14.083792) (xy -18.402554 14.173962) (xy -18.269712 14.279118) (xy -18.178018 14.370558)
				(xy -18.112232 14.437614) (xy -18.027396 14.586204) (xy -17.924272 14.817598) (xy -17.897348 15.018766)
				(xy -17.888458 15.160498) (xy -17.906238 15.300198) (xy -17.959832 15.489936) (xy -18.057114 15.682976)
				(xy -18.231358 15.893034) (xy -18.479008 16.060928) (xy -18.689574 16.13916) (xy -18.864834 16.174466)
				(xy -19.001994 16.17726) (xy -19.118326 16.169894) (xy -19.228816 16.147542) (xy -19.45767 16.08074)
				(xy -19.611086 15.978886) (xy -19.714972 15.893034) (xy -19.798792 15.807182) (xy -19.89709 15.676372)
				(xy -19.983196 15.507716) (xy -20.0279 15.380462) (xy -20.056856 15.181834) (xy -20.051776 15.059914)
				(xy -21.77796 15.059914)
			)
			(stroke
				(width 0)
				(type default)
			)
			(fill no)
			(layer "F.CrtYd")
		)
		(fp_line
			(start -14.777974 30.150054)
			(end -21.77796 30.150054)
			(stroke
				(width 0.1)
				(type default)
			)
			(layer "F.Fab")
		)
		(fp_line
			(start -14.777974 27.420062)
			(end -14.777974 30.150054)
			(stroke
				(width 0.1)
				(type default)
			)
			(layer "F.Fab")
		)
		(fp_line
			(start -14.777974 -29.219906)
			(end -18.840958 -29.219906)
			(stroke
				(width 0.1)
				(type default)
			)
			(layer "F.Fab")
		)
		(fp_line
			(start -14.777974 -31.949898)
			(end -14.777974 -29.219906)
			(stroke
				(width 0.1)
				(type default)
			)
			(layer "F.Fab")
		)
		(fp_line
			(start -18.840958 27.420062)
			(end -14.777974 27.420062)
			(stroke
				(width 0.1)
				(type default)
			)
			(layer "F.Fab")
		)
		(fp_line
			(start -18.840958 22.649942)
			(end -18.840958 27.420062)
			(stroke
				(width 0.1)
				(type default)
			)
			(layer "F.Fab")
		)
		(fp_line
			(start -18.840958 22.649942)
			(end -19.777964 22.649942)
			(stroke
				(width 0.1)
				(type default)
			)
			(layer "F.Fab")
		)
		(fp_line
			(start -18.840958 -24.45004)
			(end -19.777964 -24.45004)
			(stroke
				(width 0.1)
				(type default)
			)
			(layer "F.Fab")
		)
		(fp_line
			(start -18.840958 -29.219906)
			(end -18.840958 -24.45004)
			(stroke
				(width 0.1)
				(type default)
			)
			(layer "F.Fab")
		)
		(fp_line
			(start -19.777964 22.649942)
			(end -18.840958 22.649942)
			(stroke
				(width 0.1)
				(type default)
			)
			(layer "F.Fab")
		)
		(fp_line
			(start -19.777964 22.649942)
			(end -19.777964 15.81658)
			(stroke
				(width 0.1)
				(type default)
			)
			(layer "F.Fab")
		)
		(fp_line
			(start -19.777964 15.81658)
			(end -19.777964 22.649942)
			(stroke
				(width 0.1)
				(type default)
			)
			(layer "F.Fab")
		)
		(fp_line
			(start -19.777964 5.100066)
			(end -19.777964 14.383258)
			(stroke
				(width 0.1)
				(type default)
			)
			(layer "F.Fab")
		)
		(fp_line
			(start -19.777964 -6.89991)
			(end -21.77796 -8.899906)
			(stroke
				(width 0.1)
				(type default)
			)
			(layer "F.Fab")
		)
		(fp_line
			(start -19.777964 -24.45004)
			(end -19.777964 -6.89991)
			(stroke
				(width 0.1)
				(type default)
			)
			(layer "F.Fab")
		)
		(fp_line
			(start -21.77796 30.150054)
			(end -21.77796 7.100062)
			(stroke
				(width 0.1)
				(type default)
			)
			(layer "F.Fab")
		)
		(fp_line
			(start -21.77796 7.100062)
			(end -19.777964 5.100066)
			(stroke
				(width 0.1)
				(type default)
			)
			(layer "F.Fab")
		)
		(fp_line
			(start -21.77796 -8.899906)
			(end -21.77796 -31.949898)
			(stroke
				(width 0.1)
				(type default)
			)
			(layer "F.Fab")
		)
		(fp_line
			(start -21.77796 -31.949898)
			(end -14.777974 -31.949898)
			(stroke
				(width 0.1)
				(type default)
			)
			(layer "F.Fab")
		)
		(fp_arc
			(start -19.777964 15.81658)
			(mid -20.051913 15.099951)
			(end -19.777964 14.383258)
			(stroke
				(width 0.1)
				(type default)
			)
			(layer "F.Fab")
		)
	)
)
